# S9S_MB_2U (Grand Teton) — schematic netlist excerpt (pin names and nets, part order shuffled) for the footprints in the layout excerpt that follows; sources: Cadence DE-HDL packaged netlist, KiCad conversion of 03242023_DA0F0TMBIJ0_F0T_Motherboard_J_brd_V01_OCP.brd

R3480  Q_RES  33.2 1% CHIP  pkg 0402LF  page 213 : A = GPU_BASE_HMC_READY_ISO ; B = GPU_BASE_HMC_READY_ISO_R
C2329  Q_CAP  0.1UF 25V 10% X7R  pkg 0402  page 211 : A = P3V3_9ZXL045_VDD ; B = GND

(kicad_pcb
	(version 20260206)
	(generator "pcbnew")
	(generator_version "10.0")
	(general
		(thickness 1.6)
		(legacy_teardrops no)
	)
	(paper "A4")
	(title_block
		(title "03242023_DA0F0TMBIJ0_F0T_Motherboard_J_brd_V01_OCP.brd")
		(comment 1 "Grand Teton / footprints 4648-4649 of 6105")
	)
	(layers
		(0 "F.Cu" signal "TOP")
		(4 "In1.Cu" signal "GND")
		(6 "In2.Cu" signal "IN1")
		(8 "In3.Cu" signal "GND1")
		(10 "In4.Cu" signal "IN2")
		(12 "In5.Cu" signal "GND2")
		(14 "In6.Cu" signal "IN3")
		(16 "In7.Cu" signal "GND3")
		(18 "In8.Cu" signal "VCC")
		(20 "In9.Cu" signal "VCC1")
		(22 "In10.Cu" signal "GND4")
		(24 "In11.Cu" signal "IN4")
		(26 "In12.Cu" signal "GND5")
		(28 "In13.Cu" signal "IN5")
		(30 "In14.Cu" signal "GND6")
		(32 "In15.Cu" signal "IN6")
		(34 "In16.Cu" signal "GND7")
		(2 "B.Cu" signal "BOTTOM")
		(9 "F.Adhes" user "F.Adhesive")
		(11 "B.Adhes" user "B.Adhesive")
		(13 "F.Paste" user "Package Geometry/Pastemask Top")
		(15 "B.Paste" user "Package Geometry/Pastemask Bottom")
		(5 "F.SilkS" user "Ref Des/Silkscreen Top")
		(7 "B.SilkS" user "Ref Des/Silkscreen Bottom")
		(1 "F.Mask" user "Board Geometry/Soldermask Top")
		(3 "B.Mask" user "Board Geometry/Soldermask Bottom")
		(17 "Dwgs.User" user "User.Drawings")
		(19 "Cmts.User" user "User.Comments")
		(21 "Eco1.User" user "User.Eco1")
		(23 "Eco2.User" user "User.Eco2")
		(25 "Edge.Cuts" user "Board Geometry/Outline")
		(27 "Margin" user)
		(31 "F.CrtYd" user "Package Geometry/Place Bound Top")
		(29 "B.CrtYd" user "Package Geometry/Place Bound Bottom")
		(35 "F.Fab" user "Ref Des/Assembly Top")
		(33 "B.Fab" user "Ref Des/Assembly Bottom")
	)
	(footprint ""
		(layer "B.Cu")
		(at 157.02788 -116.296948 180)
		(property "Reference" "R3480"
			(at 0 0 0)
			(layer "B.SilkS")
			(hide yes)
			(effects
				(font
					(size 1.27 1.27)
				)
				(justify mirror)
			)
		)
		(property "Value" ""
			(at 0 0 0)
			(layer "B.Fab")
			(effects
				(font
					(size 1.27 1.27)
				)
				(justify mirror)
			)
		)
		(duplicate_pad_numbers_are_jumpers no)
		(fp_line
			(start 0.7874 0.4064)
			(end 0.7874 -0.4064)
			(stroke
				(width 0.1524)
				(type default)
			)
			(layer "B.SilkS")
		)
		(fp_line
			(start 0.7874 -0.4064)
			(end -0.7874 -0.4064)
			(stroke
				(width 0.1524)
				(type default)
			)
			(layer "B.SilkS")
		)
		(fp_line
			(start -0.7874 0.4064)
			(end 0.7874 0.4064)
			(stroke
				(width 0.1524)
				(type default)
			)
			(layer "B.SilkS")
		)
		(fp_line
			(start -0.7874 -0.4064)
			(end -0.7874 0.4064)
			(stroke
				(width 0.1524)
				(type default)
			)
			(layer "B.SilkS")
		)
		(fp_line
			(start 0.67945 0.3048)
			(end 0.67945 -0.305054)
			(stroke
				(width 0.1)
				(type default)
			)
			(layer "B.Fab")
		)
		(fp_line
			(start 0.67945 -0.305054)
			(end 0.12065 -0.305054)
			(stroke
				(width 0.1)
				(type default)
			)
			(layer "B.Fab")
		)
		(fp_line
			(start 0.12065 0.3048)
			(end 0.67945 0.3048)
			(stroke
				(width 0.1)
				(type default)
			)
			(layer "B.Fab")
		)
		(fp_line
			(start 0.12065 0.2794)
			(end 0.12065 0.3048)
			(stroke
				(width 0.1)
				(type default)
			)
			(layer "B.Fab")
		)
		(fp_line
			(start 0.12065 -0.2794)
			(end -0.12065 -0.2794)
			(stroke
				(width 0.1)
				(type default)
			)
			(layer "B.Fab")
		)
		(fp_line
			(start 0.12065 -0.305054)
			(end 0.12065 -0.2794)
			(stroke
				(width 0.1)
				(type default)
			)
			(layer "B.Fab")
		)
		(fp_line
			(start -0.120396 0.3048)
			(end -0.120396 0.2794)
			(stroke
				(width 0.1)
				(type default)
			)
			(layer "B.Fab")
		)
		(fp_line
			(start -0.120396 0.2794)
			(end 0.12065 0.2794)
			(stroke
				(width 0.1)
				(type default)
			)
			(layer "B.Fab")
		)
		(fp_line
			(start -0.12065 -0.2794)
			(end -0.12065 -0.3048)
			(stroke
				(width 0.1)
				(type default)
			)
			(layer "B.Fab")
		)
		(fp_line
			(start -0.12065 -0.3048)
			(end -0.67945 -0.3048)
			(stroke
				(width 0.1)
				(type default)
			)
			(layer "B.Fab")
		)
		(fp_line
			(start -0.67945 0.3048)
			(end -0.120396 0.3048)
			(stroke
				(width 0.1)
				(type default)
			)
			(layer "B.Fab")
		)
		(fp_line
			(start -0.67945 -0.3048)
			(end -0.67945 0.3048)
			(stroke
				(width 0.1)
				(type default)
			)
			(layer "B.Fab")
		)
		(pad "1" smd circle
			(at 0.40005 0)
			(size 0 0)
			(layers "B.Cu" "B.Mask" "B.Paste")
			(net "GPU_BASE_HMC_READY_ISO")
		)
		(pad "2" smd circle
			(at -0.40005 0)
			(size 0 0)
			(layers "B.Cu" "B.Mask" "B.Paste")
			(net "GPU_BASE_HMC_READY_ISO_R")
		)
	)
	(footprint ""
		(layer "B.Cu")
		(at 110.874556 -416.030918 90)
		(property "Reference" "C2329"
			(at 0 0 90)
			(layer "B.SilkS")
			(hide yes)
			(effects
				(font
					(size 1.27 1.27)
				)
				(justify mirror)
			)
		)
		(property "Value" ""
			(at 0 0 90)
			(layer "B.Fab")
			(effects
				(font
					(size 1.27 1.27)
				)
				(justify mirror)
			)
		)
		(duplicate_pad_numbers_are_jumpers no)
		(fp_line
			(start 0.7874 -0.4064)
			(end -0.7874 -0.4064)
			(stroke
				(width 0.1524)
				(type default)
			)
			(layer "B.SilkS")
		)
		(fp_line
			(start -0.7874 -0.4064)
			(end -0.7874 0.4064)
			(stroke
				(width 0.1524)
				(type default)
			)
			(layer "B.SilkS")
		)
		(fp_line
			(start 0.7874 0.4064)
			(end 0.7874 -0.4064)
			(stroke
				(width 0.1524)
				(type default)
			)
			(layer "B.SilkS")
		)
		(fp_line
			(start -0.7874 0.4064)
			(end 0.7874 0.4064)
			(stroke
				(width 0.1524)
				(type default)
			)
			(layer "B.SilkS")
		)
		(fp_line
			(start 0.67945 -0.305054)
			(end 0.12065 -0.305054)
			(stroke
				(width 0.1)
				(type default)
			)
			(layer "B.Fab")
		)
		(fp_line
			(start 0.12065 -0.305054)
			(end 0.12065 -0.2794)
			(stroke
				(width 0.1)
				(type default)
			)
			(layer "B.Fab")
		)
		(fp_line
			(start -0.12065 -0.3048)
			(end -0.67945 -0.3048)
			(stroke
				(width 0.1)
				(type default)
			)
			(layer "B.Fab")
		)
		(fp_line
			(start -0.67945 -0.3048)
			(end -0.67945 0.3048)
			(stroke
				(width 0.1)
				(type default)
			)
			(layer "B.Fab")
		)
		(fp_line
			(start 0.12065 -0.2794)
			(end -0.12065 -0.2794)
			(stroke
				(width 0.1)
				(type default)
			)
			(layer "B.Fab")
		)
		(fp_line
			(start -0.12065 -0.2794)
			(end -0.12065 -0.3048)
			(stroke
				(width 0.1)
				(type default)
			)
			(layer "B.Fab")
		)
		(fp_line
			(start 0.12065 0.2794)
			(end 0.12065 0.3048)
			(stroke
				(width 0.1)
				(type default)
			)
			(layer "B.Fab")
		)
		(fp_line
			(start -0.120396 0.2794)
			(end 0.12065 0.2794)
			(stroke
				(width 0.1)
				(type default)
			)
			(layer "B.Fab")
		)
		(fp_line
			(start 0.67945 0.3048)
			(end 0.67945 -0.305054)
			(stroke
				(width 0.1)
				(type default)
			)
			(layer "B.Fab")
		)
		(fp_line
			(start 0.12065 0.3048)
			(end 0.67945 0.3048)
			(stroke
				(width 0.1)
				(type default)
			)
			(layer "B.Fab")
		)
		(fp_line
			(start -0.120396 0.3048)
			(end -0.120396 0.2794)
			(stroke
				(width 0.1)
				(type default)
			)
			(layer "B.Fab")
		)
		(fp_line
			(start -0.67945 0.3048)
			(end -0.120396 0.3048)
			(stroke
				(width 0.1)
				(type default)
			)
			(layer "B.Fab")
		)
		(pad "1" smd circle
			(at 0.40005 0 270)
			(size 0 0)
			(layers "B.Cu" "B.Mask" "B.Paste")
			(net "P3V3_9ZXL045_VDD")
		)
		(pad "2" smd circle
			(at -0.40005 0 270)
			(size 0 0)
			(layers "B.Cu" "B.Mask" "B.Paste")
			(net "GND")
		)
	)
)
